(kicad_pcb
	(version 20260206)
	(generator "pcbnew")
	(generator_version "10.0")
	(general
		(thickness 1.21888)
		(legacy_teardrops no)
	)
	(paper "A4")
	(title_block
		(title "timecard-proto-v0 — Timingcard_PCB.PcbDoc")
		(comment 1 "Time Appliance Project (Time Card) / footprint 31 of 167 (P1), pads 264-340 of 340")
	)
	(layers
		(0 "F.Cu" signal "TOP")
		(4 "In1.Cu" signal "SGND")
		(6 "In2.Cu" signal "IN1")
		(8 "In3.Cu" signal "IN2")
		(10 "In4.Cu" signal "SGND1")
		(2 "B.Cu" signal "BOTTOM")
		(9 "F.Adhes" user "F.Adhesive")
		(11 "B.Adhes" user "B.Adhesive")
		(13 "F.Paste" user "Top Paste")
		(15 "B.Paste" user "Bottom Paste")
		(5 "F.SilkS" user "Top Overlay")
		(7 "B.SilkS" user "Bottom Overlay")
		(1 "F.Mask" user "Top Solder")
		(3 "B.Mask" user "Bottom Solder")
		(17 "Dwgs.User" user "User.Drawings")
		(19 "Cmts.User" user "User.Comments")
		(21 "Eco1.User" user "User.Eco1")
		(23 "Eco2.User" user "User.Eco2")
		(25 "Edge.Cuts" user)
		(27 "Margin" user)
		(31 "F.CrtYd" user "Top Courtyard")
		(29 "B.CrtYd" user "Bottom Courtyard")
		(35 "F.Fab" user "Top Component Center")
		(33 "B.Fab" user "Bottom Component Center")
	)
	(footprint "FPGA_CONN:FPGA_CONN"
		(locked yes)
		(layer "F.Cu")
		(at 125.389655 117.45847)
		(property "Reference" "P1"
			(at -27.35726 -23.285325 0)
			(unlocked yes)
			(layer "F.SilkS")
			(effects
				(font
					(size 0.762 0.762)
					(thickness 0.2286)
				)
				(justify left bottom)
			)
		)
		(property "Value" "FPGA_CONN"
			(at -43.9575 52.70297 0)
			(unlocked yes)
			(layer "F.SilkS")
			(hide yes)
			(effects
				(font
					(size 1.524 1.524)
					(thickness 0.254)
				)
				(justify left bottom)
			)
		)
		(sheetname "FPGA")
		(sheetfile "FPGA.kicad_sch")
		(duplicate_pad_numbers_are_jumpers no)
		(pad "D-12" smd rect
			(at 6.29882 20.82013)
			(size 0.24994 1.54991)
			(layers "F.Cu" "F.Mask" "F.Paste")
			(net "PCIE_TX2_P")
		)
		(pad "D-13" smd rect
			(at 5.79895 16.77035)
			(size 0.24994 1.54991)
			(layers "F.Cu" "F.Mask" "F.Paste")
		)
		(pad "D-14" smd rect
			(at 5.79895 20.82013)
			(size 0.24994 1.54991)
			(layers "F.Cu" "F.Mask" "F.Paste")
			(net "PCIE_TX2_N")
		)
		(pad "D-15" smd rect
			(at 5.29882 16.77035)
			(size 0.24994 1.54991)
			(layers "F.Cu" "F.Mask" "F.Paste")
			(net "GND")
		)
		(pad "D-16" smd rect
			(at 5.29882 20.82013)
			(size 0.24994 1.54991)
			(layers "F.Cu" "F.Mask" "F.Paste")
		)
		(pad "D-17" smd rect
			(at 4.79895 16.77035)
			(size 0.24994 1.54991)
			(layers "F.Cu" "F.Mask" "F.Paste")
			(net "PCIE_TX3_P")
		)
		(pad "D-18" smd rect
			(at 4.79895 20.82013)
			(size 0.24994 1.54991)
			(layers "F.Cu" "F.Mask" "F.Paste")
			(net "PCIE_RX2_P")
		)
		(pad "D-19" smd rect
			(at 4.29882 16.77035)
			(size 0.24994 1.54991)
			(layers "F.Cu" "F.Mask" "F.Paste")
			(net "PCIE_TX3_N")
		)
		(pad "D-20" smd rect
			(at 4.29882 20.82013)
			(size 0.24994 1.54991)
			(layers "F.Cu" "F.Mask" "F.Paste")
			(net "PCIE_RX2_N")
		)
		(pad "D-21" smd rect
			(at 3.79895 16.77035)
			(size 0.24994 1.54991)
			(layers "F.Cu" "F.Mask" "F.Paste")
			(net "GND")
		)
		(pad "D-22" smd rect
			(at 3.79895 20.82013)
			(size 0.24994 1.54991)
			(layers "F.Cu" "F.Mask" "F.Paste")
		)
		(pad "D-23" smd rect
			(at 3.29882 16.77035)
			(size 0.24994 1.54991)
			(layers "F.Cu" "F.Mask" "F.Paste")
			(net "PCIE_RX3_P")
		)
		(pad "D-24" smd rect
			(at 3.29882 20.82013)
			(size 0.24994 1.54991)
			(layers "F.Cu" "F.Mask" "F.Paste")
			(net "PCIE_TX1_P")
		)
		(pad "D-25" smd rect
			(at 2.79895 16.77035)
			(size 0.24994 1.54991)
			(layers "F.Cu" "F.Mask" "F.Paste")
			(net "PCIE_RX3_N")
		)
		(pad "D-26" smd rect
			(at 2.79895 20.82013)
			(size 0.24994 1.54991)
			(layers "F.Cu" "F.Mask" "F.Paste")
			(net "PCIE_TX1_N")
		)
		(pad "D-27" smd rect
			(at 2.29883 16.77035)
			(size 0.24994 1.54991)
			(layers "F.Cu" "F.Mask" "F.Paste")
			(net "GND")
		)
		(pad "D-28" smd rect
			(at 2.29883 20.82013)
			(size 0.24994 1.54991)
			(layers "F.Cu" "F.Mask" "F.Paste")
		)
		(pad "D-29" smd rect
			(at 1.79895 16.77035)
			(size 0.24994 1.54991)
			(layers "F.Cu" "F.Mask" "F.Paste")
			(net "PCIE_TX0_P")
		)
		(pad "D-30" smd rect
			(at 1.79895 20.82013)
			(size 0.24994 1.54991)
			(layers "F.Cu" "F.Mask" "F.Paste")
			(net "PCIE_RX1_P")
		)
		(pad "D-31" smd rect
			(at 1.29883 16.77035)
			(size 0.24994 1.54991)
			(layers "F.Cu" "F.Mask" "F.Paste")
			(net "PCIE_TX0_N")
		)
		(pad "D-32" smd rect
			(at 1.29883 20.82013)
			(size 0.24994 1.54991)
			(layers "F.Cu" "F.Mask" "F.Paste")
			(net "PCIE_RX1_N")
		)
		(pad "D-33" smd rect
			(at 0.79896 16.77035)
			(size 0.24994 1.54991)
			(layers "F.Cu" "F.Mask" "F.Paste")
			(net "GND")
		)
		(pad "D-34" smd rect
			(at 0.79896 20.82013)
			(size 0.24994 1.54991)
			(layers "F.Cu" "F.Mask" "F.Paste")
		)
		(pad "D-35" smd rect
			(at 0.29883 16.77035)
			(size 0.24994 1.54991)
			(layers "F.Cu" "F.Mask" "F.Paste")
			(net "PCIE_RX0_P")
		)
		(pad "D-36" smd rect
			(at 0.29883 20.82013)
			(size 0.24994 1.54991)
			(layers "F.Cu" "F.Mask" "F.Paste")
			(net "PCIE_CLK_P")
		)
		(pad "D-37" smd rect
			(at -0.20104 16.77035)
			(size 0.24994 1.54991)
			(layers "F.Cu" "F.Mask" "F.Paste")
			(net "PCIE_RX0_N")
		)
		(pad "D-38" smd rect
			(at -0.20104 20.82013)
			(size 0.24994 1.54991)
			(layers "F.Cu" "F.Mask" "F.Paste")
			(net "PCIE_CLK_N")
		)
		(pad "D-39" smd rect
			(at -0.70117 16.77035)
			(size 0.24994 1.54991)
			(layers "F.Cu" "F.Mask" "F.Paste")
			(net "GND")
		)
		(pad "D-40" smd rect
			(at -0.70117 20.82013)
			(size 0.24994 1.54991)
			(layers "F.Cu" "F.Mask" "F.Paste")
			(net "GND")
		)
		(pad "D-41" smd rect
			(at -1.20104 16.77035)
			(size 0.24994 1.54991)
			(layers "F.Cu" "F.Mask" "F.Paste")
		)
		(pad "D-42" smd rect
			(at -1.20104 20.82013)
			(size 0.24994 1.54991)
			(layers "F.Cu" "F.Mask" "F.Paste")
		)
		(pad "D-43" smd rect
			(at -1.70117 16.77035)
			(size 0.24994 1.54991)
			(layers "F.Cu" "F.Mask" "F.Paste")
		)
		(pad "D-44" smd rect
			(at -1.70117 20.82013)
			(size 0.24994 1.54991)
			(layers "F.Cu" "F.Mask" "F.Paste")
		)
		(pad "D-45" smd rect
			(at -2.20104 16.77035)
			(size 0.24994 1.54991)
			(layers "F.Cu" "F.Mask" "F.Paste")
		)
		(pad "D-46" smd rect
			(at -2.20104 20.82013)
			(size 0.24994 1.54991)
			(layers "F.Cu" "F.Mask" "F.Paste")
		)
		(pad "D-47" smd rect
			(at -2.70116 16.77035)
			(size 0.24994 1.54991)
			(layers "F.Cu" "F.Mask" "F.Paste")
		)
		(pad "D-48" smd rect
			(at -2.70116 20.82013)
			(size 0.24994 1.54991)
			(layers "F.Cu" "F.Mask" "F.Paste")
		)
		(pad "D-49" smd rect
			(at -3.20104 16.77035)
			(size 0.24994 1.54991)
			(layers "F.Cu" "F.Mask" "F.Paste")
			(net "GND")
		)
		(pad "D-50" smd rect
			(at -3.20104 20.82013)
			(size 0.24994 1.54991)
			(layers "F.Cu" "F.Mask" "F.Paste")
			(net "GND")
		)
		(pad "D-51" smd rect
			(at -3.70116 16.77035)
			(size 0.24994 1.54991)
			(layers "F.Cu" "F.Mask" "F.Paste")
		)
		(pad "D-52" smd rect
			(at -3.70116 20.82013)
			(size 0.24994 1.54991)
			(layers "F.Cu" "F.Mask" "F.Paste")
		)
		(pad "D-53" smd rect
			(at -4.20103 16.77035)
			(size 0.24994 1.54991)
			(layers "F.Cu" "F.Mask" "F.Paste")
		)
		(pad "D-54" smd rect
			(at -4.20103 20.82013)
			(size 0.24994 1.54991)
			(layers "F.Cu" "F.Mask" "F.Paste")
		)
		(pad "D-55" smd rect
			(at -4.70116 16.77035)
			(size 0.24994 1.54991)
			(layers "F.Cu" "F.Mask" "F.Paste")
		)
		(pad "D-56" smd rect
			(at -4.70116 20.82013)
			(size 0.24994 1.54991)
			(layers "F.Cu" "F.Mask" "F.Paste")
		)
		(pad "D-57" smd rect
			(at -5.20103 16.77035)
			(size 0.24994 1.54991)
			(layers "F.Cu" "F.Mask" "F.Paste")
		)
		(pad "D-58" smd rect
			(at -5.20103 20.82013)
			(size 0.24994 1.54991)
			(layers "F.Cu" "F.Mask" "F.Paste")
		)
		(pad "D-59" smd rect
			(at -5.70116 16.77035)
			(size 0.24994 1.54991)
			(layers "F.Cu" "F.Mask" "F.Paste")
			(net "GND")
		)
		(pad "D-60" smd rect
			(at -5.70116 20.82013)
			(size 0.24994 1.54991)
			(layers "F.Cu" "F.Mask" "F.Paste")
			(net "GND")
		)
		(pad "D-61" smd rect
			(at -6.20103 16.77035)
			(size 0.24994 1.54991)
			(layers "F.Cu" "F.Mask" "F.Paste")
		)
		(pad "D-62" smd rect
			(at -6.20103 20.82013)
			(size 0.24994 1.54991)
			(layers "F.Cu" "F.Mask" "F.Paste")
		)
		(pad "D-63" smd rect
			(at -6.70116 16.77035)
			(size 0.24994 1.54991)
			(layers "F.Cu" "F.Mask" "F.Paste")
		)
		(pad "D-64" smd rect
			(at -6.70116 20.82013)
			(size 0.24994 1.54991)
			(layers "F.Cu" "F.Mask" "F.Paste")
		)
		(pad "D-65" smd rect
			(at -7.20103 16.77035)
			(size 0.24994 1.54991)
			(layers "F.Cu" "F.Mask" "F.Paste")
		)
		(pad "D-66" smd rect
			(at -7.20103 20.82013)
			(size 0.24994 1.54991)
			(layers "F.Cu" "F.Mask" "F.Paste")
		)
		(pad "D-67" smd rect
			(at -7.70115 16.77035)
			(size 0.24994 1.54991)
			(layers "F.Cu" "F.Mask" "F.Paste")
		)
		(pad "D-68" smd rect
			(at -7.70115 20.82013)
			(size 0.24994 1.54991)
			(layers "F.Cu" "F.Mask" "F.Paste")
		)
		(pad "D-69" smd rect
			(at -8.20103 16.77035)
			(size 0.24994 1.54991)
			(layers "F.Cu" "F.Mask" "F.Paste")
			(net "GND")
		)
		(pad "D-70" smd rect
			(at -8.20103 20.82013)
			(size 0.24994 1.54991)
			(layers "F.Cu" "F.Mask" "F.Paste")
			(net "GND")
		)
		(pad "D-71" smd rect
			(at -8.70115 16.77035)
			(size 0.24994 1.54991)
			(layers "F.Cu" "F.Mask" "F.Paste")
		)
		(pad "D-72" smd rect
			(at -8.70115 20.82013)
			(size 0.24994 1.54991)
			(layers "F.Cu" "F.Mask" "F.Paste")
		)
		(pad "D-73" smd rect
			(at -9.20102 16.77035)
			(size 0.24994 1.54991)
			(layers "F.Cu" "F.Mask" "F.Paste")
		)
		(pad "D-74" smd rect
			(at -9.20102 20.82013)
			(size 0.24994 1.54991)
			(layers "F.Cu" "F.Mask" "F.Paste")
		)
		(pad "D-75" smd rect
			(at -9.70115 16.77035)
			(size 0.24994 1.54991)
			(layers "F.Cu" "F.Mask" "F.Paste")
		)
		(pad "D-76" smd rect
			(at -9.70115 20.82013)
			(size 0.24994 1.54991)
			(layers "F.Cu" "F.Mask" "F.Paste")
		)
		(pad "D-77" smd rect
			(at -10.20102 16.77035)
			(size 0.24994 1.54991)
			(layers "F.Cu" "F.Mask" "F.Paste")
		)
		(pad "D-78" smd rect
			(at -10.20102 20.82013)
			(size 0.24994 1.54991)
			(layers "F.Cu" "F.Mask" "F.Paste")
		)
		(pad "D-79" smd rect
			(at -10.70115 16.77035)
			(size 0.24994 1.54991)
			(layers "F.Cu" "F.Mask" "F.Paste")
		)
		(pad "D-80" smd rect
			(at -10.70115 20.82013)
			(size 0.24994 1.54991)
			(layers "F.Cu" "F.Mask" "F.Paste")
		)
		(pad "D-81" smd rect
			(at 10.225 18.8)
			(size 1.35001 1.70002)
			(layers "F.Cu" "F.Mask" "F.Paste")
		)
		(pad "D-82" thru_hole circle
			(at 9.04888 18.79524)
			(size 0.55016 0.55016)
			(drill 0.55016)
			(layers "*.Cu" "*.Mask")
			(remove_unused_layers no)
			(thermal_bridge_angle 90)
		)
		(pad "D-83" thru_hole circle
			(at -10.95108 18.79524)
			(size 0.55016 0.55016)
			(drill 0.55016)
			(layers "*.Cu" "*.Mask")
			(remove_unused_layers no)
			(thermal_bridge_angle 90)
		)
		(pad "D-84" smd rect
			(at -12.125 18.8)
			(size 1.35001 1.70002)
			(layers "F.Cu" "F.Mask" "F.Paste")
		)
		(pad "MNT-1" thru_hole rect
			(at -24.95156 -20.00834)
			(size 0 0)
			(drill 2.99999)
			(layers "*.Cu" "*.Mask")
			(remove_unused_layers no)
		)
		(pad "MNT-2" thru_hole rect
			(at 24.98484 -20.00834)
			(size 0 0)
			(drill 2.99999)
			(layers "*.Cu" "*.Mask")
			(remove_unused_layers no)
		)
		(pad "MNT-3" thru_hole rect
			(at 24.98484 19.86966)
			(size 0 0)
			(drill 2.99999)
			(layers "*.Cu" "*.Mask")
			(remove_unused_layers no)
		)
		(pad "MNT-4" thru_hole rect
			(at -24.92616 19.86966)
			(size 0 0)
			(drill 2.99999)
			(layers "*.Cu" "*.Mask")
			(remove_unused_layers no)
		)
	)
)
